(kicad_pcb
	(version 20260206)
	(generator "pcbnew")
	(generator_version "10.0")
	(general
		(thickness 1.6)
		(legacy_teardrops no)
	)
	(paper "A4")
	(title_block
		(title "03242023_DA0F0TMBIJ0_F0T_Motherboard_J_brd_V01_OCP.brd")
		(comment 1 "Grand Teton / footprints 996-1001 of 6105")
	)
	(layers
		(0 "F.Cu" signal "TOP")
		(4 "In1.Cu" signal "GND")
		(6 "In2.Cu" signal "IN1")
		(8 "In3.Cu" signal "GND1")
		(10 "In4.Cu" signal "IN2")
		(12 "In5.Cu" signal "GND2")
		(14 "In6.Cu" signal "IN3")
		(16 "In7.Cu" signal "GND3")
		(18 "In8.Cu" signal "VCC")
		(20 "In9.Cu" signal "VCC1")
		(22 "In10.Cu" signal "GND4")
		(24 "In11.Cu" signal "IN4")
		(26 "In12.Cu" signal "GND5")
		(28 "In13.Cu" signal "IN5")
		(30 "In14.Cu" signal "GND6")
		(32 "In15.Cu" signal "IN6")
		(34 "In16.Cu" signal "GND7")
		(2 "B.Cu" signal "BOTTOM")
		(9 "F.Adhes" user "F.Adhesive")
		(11 "B.Adhes" user "B.Adhesive")
		(13 "F.Paste" user "Package Geometry/Pastemask Top")
		(15 "B.Paste" user "Package Geometry/Pastemask Bottom")
		(5 "F.SilkS" user "Ref Des/Silkscreen Top")
		(7 "B.SilkS" user "Ref Des/Silkscreen Bottom")
		(1 "F.Mask" user "Board Geometry/Soldermask Top")
		(3 "B.Mask" user "Board Geometry/Soldermask Bottom")
		(17 "Dwgs.User" user "User.Drawings")
		(19 "Cmts.User" user "User.Comments")
		(21 "Eco1.User" user "User.Eco1")
		(23 "Eco2.User" user "User.Eco2")
		(25 "Edge.Cuts" user "Board Geometry/Outline")
		(27 "Margin" user)
		(31 "F.CrtYd" user "Package Geometry/Place Bound Top")
		(29 "B.CrtYd" user "Package Geometry/Place Bound Bottom")
		(35 "F.Fab" user "Ref Des/Assembly Top")
		(33 "B.Fab" user "Ref Des/Assembly Bottom")
	)
	(footprint ""
		(layer "F.Cu")
		(at 114.706654 -362.618528)
		(property "Reference" "PC552"
			(at 0 0 0)
			(layer "F.SilkS")
			(hide yes)
			(effects
				(font
					(size 1.27 1.27)
				)
			)
		)
		(property "Value" ""
			(at 0 0 0)
			(layer "F.Fab")
			(effects
				(font
					(size 1.27 1.27)
				)
			)
		)
		(duplicate_pad_numbers_are_jumpers no)
		(fp_line
			(start -0.7874 -0.4064)
			(end 0.7874 -0.4064)
			(stroke
				(width 0.1524)
				(type default)
			)
			(layer "F.SilkS")
		)
		(fp_line
			(start -0.7874 0.4064)
			(end -0.7874 -0.4064)
			(stroke
				(width 0.1524)
				(type default)
			)
			(layer "F.SilkS")
		)
		(fp_line
			(start 0.7874 -0.4064)
			(end 0.7874 0.4064)
			(stroke
				(width 0.1524)
				(type default)
			)
			(layer "F.SilkS")
		)
		(fp_line
			(start 0.7874 0.4064)
			(end -0.7874 0.4064)
			(stroke
				(width 0.1524)
				(type default)
			)
			(layer "F.SilkS")
		)
		(fp_line
			(start -0.67945 -0.305054)
			(end -0.12065 -0.305054)
			(stroke
				(width 0.1)
				(type default)
			)
			(layer "F.Fab")
		)
		(fp_line
			(start -0.67945 0.3048)
			(end -0.67945 -0.305054)
			(stroke
				(width 0.1)
				(type default)
			)
			(layer "F.Fab")
		)
		(fp_line
			(start -0.12065 -0.305054)
			(end -0.12065 -0.2794)
			(stroke
				(width 0.1)
				(type default)
			)
			(layer "F.Fab")
		)
		(fp_line
			(start -0.12065 -0.2794)
			(end 0.12065 -0.2794)
			(stroke
				(width 0.1)
				(type default)
			)
			(layer "F.Fab")
		)
		(fp_line
			(start -0.12065 0.2794)
			(end -0.12065 0.3048)
			(stroke
				(width 0.1)
				(type default)
			)
			(layer "F.Fab")
		)
		(fp_line
			(start -0.12065 0.3048)
			(end -0.67945 0.3048)
			(stroke
				(width 0.1)
				(type default)
			)
			(layer "F.Fab")
		)
		(fp_line
			(start 0.120396 0.2794)
			(end -0.12065 0.2794)
			(stroke
				(width 0.1)
				(type default)
			)
			(layer "F.Fab")
		)
		(fp_line
			(start 0.120396 0.3048)
			(end 0.120396 0.2794)
			(stroke
				(width 0.1)
				(type default)
			)
			(layer "F.Fab")
		)
		(fp_line
			(start 0.12065 -0.3048)
			(end 0.67945 -0.3048)
			(stroke
				(width 0.1)
				(type default)
			)
			(layer "F.Fab")
		)
		(fp_line
			(start 0.12065 -0.2794)
			(end 0.12065 -0.3048)
			(stroke
				(width 0.1)
				(type default)
			)
			(layer "F.Fab")
		)
		(fp_line
			(start 0.67945 -0.3048)
			(end 0.67945 0.3048)
			(stroke
				(width 0.1)
				(type default)
			)
			(layer "F.Fab")
		)
		(fp_line
			(start 0.67945 0.3048)
			(end 0.120396 0.3048)
			(stroke
				(width 0.1)
				(type default)
			)
			(layer "F.Fab")
		)
		(pad "1" smd circle
			(at -0.40005 0)
			(size 0 0)
			(layers "F.Cu" "F.Mask" "F.Paste")
			(net "PVCCIN_CPU1_VCC")
		)
		(pad "2" smd circle
			(at 0.40005 0)
			(size 0 0)
			(layers "F.Cu" "F.Mask" "F.Paste")
			(net "GND")
		)
	)
	(footprint ""
		(layer "F.Cu")
		(at 27.628596 -391.310876)
		(property "Reference" "R3287"
			(at 0 0 0)
			(layer "F.SilkS")
			(hide yes)
			(effects
				(font
					(size 1.27 1.27)
				)
			)
		)
		(property "Value" ""
			(at 0 0 0)
			(layer "F.Fab")
			(effects
				(font
					(size 1.27 1.27)
				)
			)
		)
		(duplicate_pad_numbers_are_jumpers no)
		(fp_line
			(start -0.7874 -0.4064)
			(end 0.7874 -0.4064)
			(stroke
				(width 0.1524)
				(type default)
			)
			(layer "F.SilkS")
		)
		(fp_line
			(start -0.7874 0.4064)
			(end -0.7874 -0.4064)
			(stroke
				(width 0.1524)
				(type default)
			)
			(layer "F.SilkS")
		)
		(fp_line
			(start 0.7874 -0.4064)
			(end 0.7874 0.4064)
			(stroke
				(width 0.1524)
				(type default)
			)
			(layer "F.SilkS")
		)
		(fp_line
			(start 0.7874 0.4064)
			(end -0.7874 0.4064)
			(stroke
				(width 0.1524)
				(type default)
			)
			(layer "F.SilkS")
		)
		(fp_line
			(start -0.67945 -0.305054)
			(end -0.12065 -0.305054)
			(stroke
				(width 0.1)
				(type default)
			)
			(layer "F.Fab")
		)
		(fp_line
			(start -0.67945 0.3048)
			(end -0.67945 -0.305054)
			(stroke
				(width 0.1)
				(type default)
			)
			(layer "F.Fab")
		)
		(fp_line
			(start -0.12065 -0.305054)
			(end -0.12065 -0.2794)
			(stroke
				(width 0.1)
				(type default)
			)
			(layer "F.Fab")
		)
		(fp_line
			(start -0.12065 -0.2794)
			(end 0.12065 -0.2794)
			(stroke
				(width 0.1)
				(type default)
			)
			(layer "F.Fab")
		)
		(fp_line
			(start -0.12065 0.2794)
			(end -0.12065 0.3048)
			(stroke
				(width 0.1)
				(type default)
			)
			(layer "F.Fab")
		)
		(fp_line
			(start -0.12065 0.3048)
			(end -0.67945 0.3048)
			(stroke
				(width 0.1)
				(type default)
			)
			(layer "F.Fab")
		)
		(fp_line
			(start 0.120396 0.2794)
			(end -0.12065 0.2794)
			(stroke
				(width 0.1)
				(type default)
			)
			(layer "F.Fab")
		)
		(fp_line
			(start 0.120396 0.3048)
			(end 0.120396 0.2794)
			(stroke
				(width 0.1)
				(type default)
			)
			(layer "F.Fab")
		)
		(fp_line
			(start 0.12065 -0.3048)
			(end 0.67945 -0.3048)
			(stroke
				(width 0.1)
				(type default)
			)
			(layer "F.Fab")
		)
		(fp_line
			(start 0.12065 -0.2794)
			(end 0.12065 -0.3048)
			(stroke
				(width 0.1)
				(type default)
			)
			(layer "F.Fab")
		)
		(fp_line
			(start 0.67945 -0.3048)
			(end 0.67945 0.3048)
			(stroke
				(width 0.1)
				(type default)
			)
			(layer "F.Fab")
		)
		(fp_line
			(start 0.67945 0.3048)
			(end 0.120396 0.3048)
			(stroke
				(width 0.1)
				(type default)
			)
			(layer "F.Fab")
		)
		(pad "1" smd circle
			(at -0.40005 0)
			(size 0 0)
			(layers "F.Cu" "F.Mask" "F.Paste")
			(net "FM_P2E_SWB")
		)
		(pad "2" smd circle
			(at 0.40005 0)
			(size 0 0)
			(layers "F.Cu" "F.Mask" "F.Paste")
			(net "GND")
		)
	)
	(footprint ""
		(layer "F.Cu")
		(at 323.72808 -21.046948 -90)
		(property "Reference" "R4099"
			(at 0 0 270)
			(layer "F.SilkS")
			(hide yes)
			(effects
				(font
					(size 1.27 1.27)
				)
			)
		)
		(property "Value" ""
			(at 0 0 270)
			(layer "F.Fab")
			(effects
				(font
					(size 1.27 1.27)
				)
			)
		)
		(duplicate_pad_numbers_are_jumpers no)
		(fp_line
			(start -0.7874 0.4064)
			(end -0.7874 -0.4064)
			(stroke
				(width 0.1524)
				(type default)
			)
			(layer "F.SilkS")
		)
		(fp_line
			(start 0.7874 0.4064)
			(end -0.7874 0.4064)
			(stroke
				(width 0.1524)
				(type default)
			)
			(layer "F.SilkS")
		)
		(fp_line
			(start -0.7874 -0.4064)
			(end 0.7874 -0.4064)
			(stroke
				(width 0.1524)
				(type default)
			)
			(layer "F.SilkS")
		)
		(fp_line
			(start 0.7874 -0.4064)
			(end 0.7874 0.4064)
			(stroke
				(width 0.1524)
				(type default)
			)
			(layer "F.SilkS")
		)
		(fp_line
			(start -0.67945 0.3048)
			(end -0.67945 -0.305054)
			(stroke
				(width 0.1)
				(type default)
			)
			(layer "F.Fab")
		)
		(fp_line
			(start -0.12065 0.3048)
			(end -0.67945 0.3048)
			(stroke
				(width 0.1)
				(type default)
			)
			(layer "F.Fab")
		)
		(fp_line
			(start 0.120396 0.3048)
			(end 0.120396 0.2794)
			(stroke
				(width 0.1)
				(type default)
			)
			(layer "F.Fab")
		)
		(fp_line
			(start 0.67945 0.3048)
			(end 0.120396 0.3048)
			(stroke
				(width 0.1)
				(type default)
			)
			(layer "F.Fab")
		)
		(fp_line
			(start -0.12065 0.2794)
			(end -0.12065 0.3048)
			(stroke
				(width 0.1)
				(type default)
			)
			(layer "F.Fab")
		)
		(fp_line
			(start 0.120396 0.2794)
			(end -0.12065 0.2794)
			(stroke
				(width 0.1)
				(type default)
			)
			(layer "F.Fab")
		)
		(fp_line
			(start -0.12065 -0.2794)
			(end 0.12065 -0.2794)
			(stroke
				(width 0.1)
				(type default)
			)
			(layer "F.Fab")
		)
		(fp_line
			(start 0.12065 -0.2794)
			(end 0.12065 -0.3048)
			(stroke
				(width 0.1)
				(type default)
			)
			(layer "F.Fab")
		)
		(fp_line
			(start 0.12065 -0.3048)
			(end 0.67945 -0.3048)
			(stroke
				(width 0.1)
				(type default)
			)
			(layer "F.Fab")
		)
		(fp_line
			(start 0.67945 -0.3048)
			(end 0.67945 0.3048)
			(stroke
				(width 0.1)
				(type default)
			)
			(layer "F.Fab")
		)
		(fp_line
			(start -0.67945 -0.305054)
			(end -0.12065 -0.305054)
			(stroke
				(width 0.1)
				(type default)
			)
			(layer "F.Fab")
		)
		(fp_line
			(start -0.12065 -0.305054)
			(end -0.12065 -0.2794)
			(stroke
				(width 0.1)
				(type default)
			)
			(layer "F.Fab")
		)
		(pad "1" smd circle
			(at -0.40005 0 270)
			(size 0 0)
			(layers "F.Cu" "F.Mask" "F.Paste")
			(net "PD_PCH_GPPC_A_10")
		)
		(pad "2" smd circle
			(at 0.40005 0 270)
			(size 0 0)
			(layers "F.Cu" "F.Mask" "F.Paste")
			(net "GND")
		)
	)
	(footprint ""
		(layer "F.Cu")
		(at 66.0654 -39.487348 90)
		(property "Reference" "R3827"
			(at 0 0 90)
			(layer "F.SilkS")
			(hide yes)
			(effects
				(font
					(size 1.27 1.27)
				)
			)
		)
		(property "Value" ""
			(at 0 0 90)
			(layer "F.Fab")
			(effects
				(font
					(size 1.27 1.27)
				)
			)
		)
		(duplicate_pad_numbers_are_jumpers no)
		(fp_line
			(start 0.7874 -0.4064)
			(end 0.7874 0.4064)
			(stroke
				(width 0.1524)
				(type default)
			)
			(layer "F.SilkS")
		)
		(fp_line
			(start -0.7874 -0.4064)
			(end 0.7874 -0.4064)
			(stroke
				(width 0.1524)
				(type default)
			)
			(layer "F.SilkS")
		)
		(fp_line
			(start 0.7874 0.4064)
			(end -0.7874 0.4064)
			(stroke
				(width 0.1524)
				(type default)
			)
			(layer "F.SilkS")
		)
		(fp_line
			(start -0.7874 0.4064)
			(end -0.7874 -0.4064)
			(stroke
				(width 0.1524)
				(type default)
			)
			(layer "F.SilkS")
		)
		(fp_line
			(start -0.12065 -0.305054)
			(end -0.12065 -0.2794)
			(stroke
				(width 0.1)
				(type default)
			)
			(layer "F.Fab")
		)
		(fp_line
			(start -0.67945 -0.305054)
			(end -0.12065 -0.305054)
			(stroke
				(width 0.1)
				(type default)
			)
			(layer "F.Fab")
		)
		(fp_line
			(start 0.67945 -0.3048)
			(end 0.67945 0.3048)
			(stroke
				(width 0.1)
				(type default)
			)
			(layer "F.Fab")
		)
		(fp_line
			(start 0.12065 -0.3048)
			(end 0.67945 -0.3048)
			(stroke
				(width 0.1)
				(type default)
			)
			(layer "F.Fab")
		)
		(fp_line
			(start 0.12065 -0.2794)
			(end 0.12065 -0.3048)
			(stroke
				(width 0.1)
				(type default)
			)
			(layer "F.Fab")
		)
		(fp_line
			(start -0.12065 -0.2794)
			(end 0.12065 -0.2794)
			(stroke
				(width 0.1)
				(type default)
			)
			(layer "F.Fab")
		)
		(fp_line
			(start 0.120396 0.2794)
			(end -0.12065 0.2794)
			(stroke
				(width 0.1)
				(type default)
			)
			(layer "F.Fab")
		)
		(fp_line
			(start -0.12065 0.2794)
			(end -0.12065 0.3048)
			(stroke
				(width 0.1)
				(type default)
			)
			(layer "F.Fab")
		)
		(fp_line
			(start 0.67945 0.3048)
			(end 0.120396 0.3048)
			(stroke
				(width 0.1)
				(type default)
			)
			(layer "F.Fab")
		)
		(fp_line
			(start 0.120396 0.3048)
			(end 0.120396 0.2794)
			(stroke
				(width 0.1)
				(type default)
			)
			(layer "F.Fab")
		)
		(fp_line
			(start -0.12065 0.3048)
			(end -0.67945 0.3048)
			(stroke
				(width 0.1)
				(type default)
			)
			(layer "F.Fab")
		)
		(fp_line
			(start -0.67945 0.3048)
			(end -0.67945 -0.305054)
			(stroke
				(width 0.1)
				(type default)
			)
			(layer "F.Fab")
		)
		(pad "1" smd circle
			(at -0.40005 0 90)
			(size 0 0)
			(layers "F.Cu" "F.Mask" "F.Paste")
			(net "P12V_OCP_UV_2_R")
		)
		(pad "2" smd circle
			(at 0.40005 0 90)
			(size 0 0)
			(layers "F.Cu" "F.Mask" "F.Paste")
			(net "P12V_OCP_UV_2")
		)
	)
	(footprint ""
		(layer "F.Cu")
		(at 100.92182 -99.423982)
		(property "Reference" "Q88"
			(at 1.62814 -0.742188 0)
			(unlocked yes)
			(layer "F.SilkS")
			(effects
				(font
					(size 0.7874 0.5842)
					(thickness 0.1524)
				)
				(justify left)
			)
		)
		(property "Value" ""
			(at 0 0 0)
			(layer "F.Fab")
			(effects
				(font
					(size 1.27 1.27)
				)
			)
		)
		(duplicate_pad_numbers_are_jumpers no)
		(fp_line
			(start -1.332738 -1.100074)
			(end -0.4826 -1.100074)
			(stroke
				(width 0.1524)
				(type default)
			)
			(layer "F.SilkS")
		)
		(fp_line
			(start -1.332738 1.100074)
			(end -1.332738 -1.100074)
			(stroke
				(width 0.1524)
				(type default)
			)
			(layer "F.SilkS")
		)
		(fp_line
			(start -0.4826 -1.100074)
			(end 0 -0.541274)
			(stroke
				(width 0.1524)
				(type default)
			)
			(layer "F.SilkS")
		)
		(fp_line
			(start 0 -0.541274)
			(end 0.4826 -1.100074)
			(stroke
				(width 0.1524)
				(type default)
			)
			(layer "F.SilkS")
		)
		(fp_line
			(start 0.4826 -1.100074)
			(end 1.332738 -1.100074)
			(stroke
				(width 0.1524)
				(type default)
			)
			(layer "F.SilkS")
		)
		(fp_line
			(start 1.332738 -1.100074)
			(end 1.332738 1.100074)
			(stroke
				(width 0.1524)
				(type default)
			)
			(layer "F.SilkS")
		)
		(fp_line
			(start 1.332738 1.100074)
			(end -1.332738 1.100074)
			(stroke
				(width 0.1524)
				(type default)
			)
			(layer "F.SilkS")
		)
		(fp_poly
			(pts
				(xy -0.588772 -1.917446) (xy -0.9398 -1.21539) (xy -1.290828 -1.917446)
			)
			(stroke
				(width 0)
				(type default)
			)
			(fill yes)
			(layer "F.SilkS")
		)
		(fp_line
			(start -0.674878 -1.100074)
			(end 0.674878 -1.100074)
			(stroke
				(width 0.1)
				(type default)
			)
			(layer "F.Fab")
		)
		(fp_line
			(start -0.674878 1.100074)
			(end -0.674878 -1.100074)
			(stroke
				(width 0.1)
				(type default)
			)
			(layer "F.Fab")
		)
		(fp_line
			(start 0.674878 -1.100074)
			(end 0.674878 1.100074)
			(stroke
				(width 0.1)
				(type default)
			)
			(layer "F.Fab")
		)
		(fp_line
			(start 0.674878 1.100074)
			(end -0.674878 1.100074)
			(stroke
				(width 0.1)
				(type default)
			)
			(layer "F.Fab")
		)
		(fp_poly
			(pts
				(xy -2.2352 -0.298958) (xy -2.2352 -1.001014) (xy -1.533144 -0.649986)
			)
			(stroke
				(width 0)
				(type default)
			)
			(fill yes)
			(layer "F.Fab")
		)
		(pad "1" smd rect
			(at -0.94996 -0.649986 90)
			(size 0.4318 0.508)
			(layers "F.Cu" "F.Mask" "F.Paste")
			(net "GND")
		)
		(pad "2" smd rect
			(at -0.94996 0 90)
			(size 0.4318 0.508)
			(layers "F.Cu" "F.Mask" "F.Paste")
			(net "PWRGD_CPUPWRGD_LVC2_R1")
		)
		(pad "3" smd rect
			(at -0.94996 0.649986 90)
			(size 0.4318 0.508)
			(layers "F.Cu" "F.Mask" "F.Paste")
			(net "LED_RST_PLTRST_N_D")
		)
		(pad "4" smd rect
			(at 0.94996 0.649986 90)
			(size 0.4318 0.508)
			(layers "F.Cu" "F.Mask" "F.Paste")
			(net "GND")
		)
		(pad "5" smd rect
			(at 0.94996 0 90)
			(size 0.4318 0.508)
			(layers "F.Cu" "F.Mask" "F.Paste")
			(net "RST_PLTRST_N")
		)
		(pad "6" smd rect
			(at 0.94996 -0.649986 90)
			(size 0.4318 0.508)
			(layers "F.Cu" "F.Mask" "F.Paste")
			(net "LED_PWRGD_CPUPWRGD_GTL_D")
		)
	)
	(footprint ""
		(layer "F.Cu")
		(at 106.3117 -255.0541 90)
		(property "Reference" "C283"
			(at 0 0 90)
			(layer "F.SilkS")
			(hide yes)
			(effects
				(font
					(size 1.27 1.27)
				)
			)
		)
		(property "Value" ""
			(at 0 0 90)
			(layer "F.Fab")
			(effects
				(font
					(size 1.27 1.27)
				)
			)
		)
		(duplicate_pad_numbers_are_jumpers no)
		(fp_line
			(start 0.7874 -0.4064)
			(end 0.7874 0.4064)
			(stroke
				(width 0.1524)
				(type default)
			)
			(layer "F.SilkS")
		)
		(fp_line
			(start -0.7874 -0.4064)
			(end 0.7874 -0.4064)
			(stroke
				(width 0.1524)
				(type default)
			)
			(layer "F.SilkS")
		)
		(fp_line
			(start 0.7874 0.4064)
			(end -0.7874 0.4064)
			(stroke
				(width 0.1524)
				(type default)
			)
			(layer "F.SilkS")
		)
		(fp_line
			(start -0.7874 0.4064)
			(end -0.7874 -0.4064)
			(stroke
				(width 0.1524)
				(type default)
			)
			(layer "F.SilkS")
		)
		(fp_line
			(start -0.12065 -0.305054)
			(end -0.12065 -0.2794)
			(stroke
				(width 0.1)
				(type default)
			)
			(layer "F.Fab")
		)
		(fp_line
			(start -0.67945 -0.305054)
			(end -0.12065 -0.305054)
			(stroke
				(width 0.1)
				(type default)
			)
			(layer "F.Fab")
		)
		(fp_line
			(start 0.67945 -0.3048)
			(end 0.67945 0.3048)
			(stroke
				(width 0.1)
				(type default)
			)
			(layer "F.Fab")
		)
		(fp_line
			(start 0.12065 -0.3048)
			(end 0.67945 -0.3048)
			(stroke
				(width 0.1)
				(type default)
			)
			(layer "F.Fab")
		)
		(fp_line
			(start 0.12065 -0.2794)
			(end 0.12065 -0.3048)
			(stroke
				(width 0.1)
				(type default)
			)
			(layer "F.Fab")
		)
		(fp_line
			(start -0.12065 -0.2794)
			(end 0.12065 -0.2794)
			(stroke
				(width 0.1)
				(type default)
			)
			(layer "F.Fab")
		)
		(fp_line
			(start 0.120396 0.2794)
			(end -0.12065 0.2794)
			(stroke
				(width 0.1)
				(type default)
			)
			(layer "F.Fab")
		)
		(fp_line
			(start -0.12065 0.2794)
			(end -0.12065 0.3048)
			(stroke
				(width 0.1)
				(type default)
			)
			(layer "F.Fab")
		)
		(fp_line
			(start 0.67945 0.3048)
			(end 0.120396 0.3048)
			(stroke
				(width 0.1)
				(type default)
			)
			(layer "F.Fab")
		)
		(fp_line
			(start 0.120396 0.3048)
			(end 0.120396 0.2794)
			(stroke
				(width 0.1)
				(type default)
			)
			(layer "F.Fab")
		)
		(fp_line
			(start -0.12065 0.3048)
			(end -0.67945 0.3048)
			(stroke
				(width 0.1)
				(type default)
			)
			(layer "F.Fab")
		)
		(fp_line
			(start -0.67945 0.3048)
			(end -0.67945 -0.305054)
			(stroke
				(width 0.1)
				(type default)
			)
			(layer "F.Fab")
		)
		(pad "1" smd circle
			(at -0.40005 0 90)
			(size 0 0)
			(layers "F.Cu" "F.Mask" "F.Paste")
			(net "PVCCIN_CPU1")
		)
		(pad "2" smd circle
			(at 0.40005 0 90)
			(size 0 0)
			(layers "F.Cu" "F.Mask" "F.Paste")
			(net "GND")
		)
	)
)
